FILE_TYPE = MULTI_PHYS_TABLE;

PART 'NC7SB3157'

{========================================================================================}
:VALUE          | MANUF_PN       | PACK_TYPE | MATERIAL | PART_NUMBER       = STANDARD        | LIFECYCLE      | ENVCOMP | PART_NUMBER       | JEDEC_TYPE | CLASS | DESCRIPTION                              | HEIGHT   | COMPONENT_TYPE | LEAD_LENGTH | LPID | DAY        ;
{========================================================================================}
 'NC7SB3157P6X' | 'NC7SB3157P6X' | 'SMLF'    | 'IC'     | 'ALSB3157000'(!)  = 'End of Design' | 'Comp-Approve' | 'YES'   | 'ALSB3157000'     |'SC70-6'| 'IC'  | 'IC(6P) NC7SB3157P6X(SC70-6)'            | '.044IN' | 'SMALLSMT'     | ''          | ''   | '20100709'
 'NC7SB3157P6X' | 'NC7SB3157P6X' | 'SMLF'    | 'EMPTY'  | 'ALSB3157000'(!)  = 'End of Design' | 'Comp-Approve' | 'YES'   | 'ALSB3157000'     |'SC70-6'| 'IO'  | 'IC(6P) NC7SB3157P6X(SC70-6)'            | '.044IN' | 'SMALLSMT'     | ''          | ''   | '20100709'
 'NC7SB3157P6X' | 'NC7SB3157P6X' | 'SMLF'    | 'IC'     | 'ALSB3157000SEL1'(!) = ''              | ''               | ''      | 'ALSB3157000SEL1' |'SC70-6'| 'IC'  | 'IC OTHER(6P)NC7SB3157P6X(SC70-6)SELASN' | ''       | ''             | ''          | ''   | '20230726'
 'NC7SB3157P6X' | 'NC7SB3157P6X' | 'SMLF'    | 'EMPTY'  | 'ALSB3157000SEL1'(!) = ''              | ''               | ''      | 'ALSB3157000SEL1' |'SC70-6'| 'IC'  | 'IC OTHER(6P)NC7SB3157P6X(SC70-6)SELASN' | ''       | ''             | ''          | ''   | '20230726'

END_PART

END.

